# ZAIUS-LV CARD-DVT-X01-BOM-X00_20170420_Final.xls.xlsx — TBD AVL Qual (bom)
| NOTES: |  |  |  |  |  |  |
| The following items are alternates to the items listed in the Critical Components Qual tab. |  |  |  |  |  |  |
| These components will be included on near future, non-customer builds for validation and approval by both Customer and the ODM. |  |  |  |  |  |  |
| Item Description | ODM P/N | Customer PN | Vendor | Vendor PN | Build ?? | Estimated Completion Date |
| SATA connectors (black) |  |  |  |  |  |  |
| -  Alternate |  |  |  |  |  |  |
| SATA connectors (blue) |  |  |  |  |  |  |
| -  Alternate |  |  |  |  |  |  |
| PCIe retention |  |  |  |  |  |  |
| -  Alternate |  |  |  |  |  |  |
| RTC XTAL |  |  |  |  |  |  |
| -  Alternate |  |  |  |  |  |  |
| XTAL |  |  |  |  |  |  |
| -  Alternate |  |  |  |  |  |  |
